(kicad_pcb
	(version 20260206)
	(generator "pcbnew")
	(generator_version "10.0")
	(general
		(thickness 1.21888)
		(legacy_teardrops no)
	)
	(paper "A4")
	(title_block
		(title "timecard-v8 — TimeCard-DC-V8_EXP.PcbDoc")
		(comment 1 "Time Appliance Project (Time Card) / footprints 159-167 of 288")
	)
	(layers
		(0 "F.Cu" signal "TOP")
		(4 "In1.Cu" signal "SGND")
		(6 "In2.Cu" signal "IN1")
		(8 "In3.Cu" signal "IN2")
		(10 "In4.Cu" signal "SGND1")
		(2 "B.Cu" signal "BOTTOM")
		(9 "F.Adhes" user "F.Adhesive")
		(11 "B.Adhes" user "B.Adhesive")
		(13 "F.Paste" user "Top Paste")
		(15 "B.Paste" user "Bottom Paste")
		(5 "F.SilkS" user "Top Overlay")
		(7 "B.SilkS" user "Bottom Overlay")
		(1 "F.Mask" user "Top Solder")
		(3 "B.Mask" user "Bottom Solder")
		(17 "Dwgs.User" user "User.Drawings")
		(19 "Cmts.User" user "User.Comments")
		(21 "Eco1.User" user "User.Eco1")
		(23 "Eco2.User" user "User.Eco2")
		(25 "Edge.Cuts" user)
		(27 "Margin" user)
		(31 "F.CrtYd" user "Top Courtyard")
		(29 "B.CrtYd" user "Bottom Courtyard")
		(35 "F.Fab" user "Top Component Center")
		(33 "B.Fab" user "Bottom Component Center")
	)
	(footprint "Vault:FP-A6H-2102-MFG"
		(layer "F.Cu")
		(at 170.7261 86.8162)
		(property "Reference" "SW1"
			(at 2.328605 4.126921 0)
			(unlocked yes)
			(layer "F.SilkS")
			(effects
				(font
					(size 0.762 0.762)
					(thickness 0.2286)
				)
			)
		)
		(property "Value" "A6H-2102"
			(at 3.998655 6.085071 0)
			(unlocked yes)
			(layer "F.SilkS")
			(hide yes)
			(effects
				(font
					(size 0.762 0.762)
					(thickness 0.2286)
				)
			)
		)
		(sheetname "USBUart_DipSelects")
		(sheetfile "USBUart_DipSelects.kicad_sch")
		(duplicate_pad_numbers_are_jumpers no)
		(fp_line
			(start -1.985 -2.35)
			(end -1.39 -2.35)
			(stroke
				(width 0.2)
				(type solid)
			)
			(layer "F.SilkS")
		)
		(fp_line
			(start -1.985 2.35)
			(end -1.985 -2.35)
			(stroke
				(width 0.2)
				(type solid)
			)
			(layer "F.SilkS")
		)
		(fp_line
			(start -1.985 2.35)
			(end -1.39 2.35)
			(stroke
				(width 0.2)
				(type solid)
			)
			(layer "F.SilkS")
		)
		(fp_line
			(start 1.39 -2.35)
			(end 1.985 -2.35)
			(stroke
				(width 0.2)
				(type solid)
			)
			(layer "F.SilkS")
		)
		(fp_line
			(start 1.39 2.35)
			(end 1.985 2.35)
			(stroke
				(width 0.2)
				(type solid)
			)
			(layer "F.SilkS")
		)
		(fp_line
			(start 1.985 2.35)
			(end 1.985 -2.35)
			(stroke
				(width 0.2)
				(type solid)
			)
			(layer "F.SilkS")
		)
		(fp_circle
			(center -0.635 4.275)
			(end -0.635 4.15)
			(stroke
				(width 0.25)
				(type solid)
			)
			(fill no)
			(layer "F.SilkS")
		)
		(fp_line
			(start -2.085 -3.8)
			(end 2.085 -3.8)
			(stroke
				(width 0.2)
				(type solid)
			)
			(layer "F.CrtYd")
		)
		(fp_line
			(start -2.085 3.8)
			(end -2.085 -3.8)
			(stroke
				(width 0.2)
				(type solid)
			)
			(layer "F.CrtYd")
		)
		(fp_line
			(start -2.085 3.8)
			(end 2.085 3.8)
			(stroke
				(width 0.2)
				(type solid)
			)
			(layer "F.CrtYd")
		)
		(fp_line
			(start 2.085 3.8)
			(end 2.085 -3.8)
			(stroke
				(width 0.2)
				(type solid)
			)
			(layer "F.CrtYd")
		)
		(fp_line
			(start -2.085 -3.8)
			(end 2.085 -3.8)
			(stroke
				(width 0.2)
				(type solid)
			)
			(layer "F.Fab")
		)
		(fp_line
			(start -2.085 3.8)
			(end -2.085 -3.8)
			(stroke
				(width 0.2)
				(type solid)
			)
			(layer "F.Fab")
		)
		(fp_line
			(start -2.085 3.8)
			(end 2.085 3.8)
			(stroke
				(width 0.2)
				(type solid)
			)
			(layer "F.Fab")
		)
		(fp_line
			(start -0.5 0)
			(end 0.5 0)
			(stroke
				(width 0.1)
				(type solid)
			)
			(layer "F.Fab")
		)
		(fp_line
			(start 0 0.5)
			(end 0 -0.5)
			(stroke
				(width 0.1)
				(type solid)
			)
			(layer "F.Fab")
		)
		(fp_line
			(start 2.085 3.8)
			(end 2.085 -3.8)
			(stroke
				(width 0.2)
				(type solid)
			)
			(layer "F.Fab")
		)
		(fp_text user "${REFERENCE}"
			(at -0.00001 0.09602 360)
			(unlocked yes)
			(layer "F.Fab")
			(effects
				(font
					(face "Arial")
					(size 0.63 0.63)
					(thickness 0.1)
				)
				(justify left bottom)
			)
		)
		(pad "1" smd rect
			(at -0.635 3.075)
			(size 0.76 1.25)
			(layers "F.Cu" "F.Mask" "F.Paste")
			(net "GND")
			(solder_mask_margin 0)
			(solder_paste_margin 0)
		)
		(pad "2" smd rect
			(at 0.635 3.075)
			(size 0.76 1.25)
			(layers "F.Cu" "F.Mask" "F.Paste")
			(net "GND")
			(solder_mask_margin 0)
			(solder_paste_margin 0)
		)
		(pad "3" smd rect
			(at 0.635 -3.075)
			(size 0.76 1.25)
			(layers "F.Cu" "F.Mask" "F.Paste")
			(net "DIP_SW_PPS_SEL")
			(solder_mask_margin 0)
			(solder_paste_margin 0)
		)
		(pad "4" smd rect
			(at -0.635 -3.075)
			(size 0.76 1.25)
			(layers "F.Cu" "F.Mask" "F.Paste")
			(net "DIP_SW_UART_SEL")
			(solder_mask_margin 0)
			(solder_paste_margin 0)
		)
	)
	(footprint "Resistors:RESC2012X50N"
		(layer "F.Cu")
		(at 199.31136 143.47763)
		(property "Reference" "R19"
			(at -1.28526 -1.268085 0)
			(unlocked yes)
			(layer "F.SilkS")
			(effects
				(font
					(size 0.762 0.762)
					(thickness 0.2286)
				)
				(justify left bottom)
			)
		)
		(property "Value" "CRCW080533R0FKEA"
			(at -3.0249 -6.429155 0)
			(unlocked yes)
			(layer "F.SilkS")
			(hide yes)
			(effects
				(font
					(size 0.762 0.762)
					(thickness 0.2286)
				)
				(justify left bottom)
			)
		)
		(sheetname "PCIe_JTAG")
		(sheetfile "PCIe_JTAG.kicad_sch")
		(duplicate_pad_numbers_are_jumpers no)
		(fp_line
			(start 0 0.762)
			(end 0 -0.762)
			(stroke
				(width 0.1524)
				(type solid)
			)
			(layer "F.SilkS")
		)
		(pad "1" smd rect
			(at -1 0 90)
			(size 1.45 0.95)
			(layers "F.Cu" "F.Mask" "F.Paste")
			(net "FPGA_TDO")
		)
		(pad "2" smd rect
			(at 1 0 90)
			(size 1.45 0.95)
			(layers "F.Cu" "F.Mask" "F.Paste")
			(net "NetR19_2")
		)
	)
	(footprint "Vault:CAPC1005X55X25LL05T10"
		(layer "F.Cu")
		(at 234.7261 75.0162 -90)
		(property "Reference" "C87"
			(at 0.5286 4.426931 270)
			(unlocked yes)
			(layer "F.SilkS")
			(effects
				(font
					(size 0.762 0.762)
					(thickness 0.2286)
				)
			)
		)
		(property "Value" "47pF_50V_0402"
			(at -2.656031 9.61078 180)
			(unlocked yes)
			(layer "F.SilkS")
			(hide yes)
			(effects
				(font
					(size 0.762 0.762)
					(thickness 0.2286)
				)
			)
		)
		(sheetname "USBUart_DipSelects")
		(sheetfile "USBUart_DipSelects.kicad_sch")
		(duplicate_pad_numbers_are_jumpers no)
		(pad "1" smd rect
			(at -0.39 0)
			(size 0.52 0.56)
			(layers "F.Cu" "F.Mask" "F.Paste")
			(net "GND")
		)
		(pad "2" smd rect
			(at 0.39 0)
			(size 0.52 0.56)
			(layers "F.Cu" "F.Mask" "F.Paste")
			(net "FTDI_USB_R_P")
		)
	)
	(footprint "Vault:FP-C1005-050-0_05-IPC_A"
		(layer "F.Cu")
		(at 232.13262 119.2011)
		(property "Reference" "C81"
			(at 2.522085 0.042021 0)
			(unlocked yes)
			(layer "F.SilkS")
			(effects
				(font
					(size 0.762 0.762)
					(thickness 0.2286)
				)
			)
		)
		(property "Value" "2.2uF_16V_0402"
			(at 9.509005 2.440151 0)
			(unlocked yes)
			(layer "F.SilkS")
			(hide yes)
			(effects
				(font
					(size 0.762 0.762)
					(thickness 0.2286)
				)
			)
		)
		(sheetname "POWER")
		(sheetfile "POWER.kicad_sch")
		(duplicate_pad_numbers_are_jumpers no)
		(fp_line
			(start -0.83624 -0.73624)
			(end 0.83623 -0.73624)
			(stroke
				(width 0.2)
				(type solid)
			)
			(layer "F.SilkS")
		)
		(fp_line
			(start -0.83624 0.73624)
			(end 0.83623 0.73624)
			(stroke
				(width 0.2)
				(type solid)
			)
			(layer "F.SilkS")
		)
		(fp_line
			(start -1.03624 -0.53624)
			(end 1.03623 -0.53624)
			(stroke
				(width 0.2)
				(type solid)
			)
			(layer "F.CrtYd")
		)
		(fp_line
			(start -1.03624 0.53624)
			(end -1.03624 -0.53624)
			(stroke
				(width 0.2)
				(type solid)
			)
			(layer "F.CrtYd")
		)
		(fp_line
			(start -1.03624 0.53624)
			(end 1.03623 0.53624)
			(stroke
				(width 0.2)
				(type solid)
			)
			(layer "F.CrtYd")
		)
		(fp_line
			(start 1.03623 0.53624)
			(end 1.03623 -0.53624)
			(stroke
				(width 0.2)
				(type solid)
			)
			(layer "F.CrtYd")
		)
		(fp_line
			(start -1.03624 -0.53624)
			(end 1.03623 -0.53624)
			(stroke
				(width 0.2)
				(type solid)
			)
			(layer "F.Fab")
		)
		(fp_line
			(start -1.03624 0.53624)
			(end -1.03624 -0.53624)
			(stroke
				(width 0.2)
				(type solid)
			)
			(layer "F.Fab")
		)
		(fp_line
			(start -1.03624 0.53624)
			(end 1.03623 0.53624)
			(stroke
				(width 0.2)
				(type solid)
			)
			(layer "F.Fab")
		)
		(fp_line
			(start -0.5 0)
			(end 0.5 0)
			(stroke
				(width 0.1)
				(type solid)
			)
			(layer "F.Fab")
		)
		(fp_line
			(start 0 0.5)
			(end 0 -0.5)
			(stroke
				(width 0.1)
				(type solid)
			)
			(layer "F.Fab")
		)
		(fp_line
			(start 1.03623 0.53624)
			(end 1.03623 -0.53624)
			(stroke
				(width 0.2)
				(type solid)
			)
			(layer "F.Fab")
		)
		(fp_text user "${REFERENCE}"
			(at -0.00002 0.09602 360)
			(unlocked yes)
			(layer "F.Fab")
			(effects
				(font
					(face "Arial")
					(size 0.63 0.63)
					(thickness 0.1)
				)
				(justify left bottom)
			)
		)
		(pad "1" smd rect
			(at -0.46658 0)
			(size 0.73933 0.67248)
			(layers "F.Cu" "F.Mask" "F.Paste")
			(net "+3.3V")
			(solder_mask_margin 0)
			(solder_paste_margin 0)
		)
		(pad "2" smd rect
			(at 0.46657 0)
			(size 0.73933 0.67248)
			(layers "F.Cu" "F.Mask" "F.Paste")
			(net "GND")
			(solder_mask_margin 0)
			(solder_paste_margin 0)
		)
	)
	(footprint "SA53:SolderSocket"
		(layer "F.Cu")
		(at 131.8261 138.2162 90)
		(property "Reference" "SKT1"
			(at -3.426921 1.2286 0)
			(unlocked yes)
			(layer "F.SilkS")
			(effects
				(font
					(size 0.762 0.762)
					(thickness 0.2286)
				)
			)
		)
		(property "Value" "0332-0-43-80-18-27-10-0"
			(at -2.910071 16.1362 0)
			(unlocked yes)
			(layer "F.SilkS")
			(hide yes)
			(effects
				(font
					(size 0.762 0.762)
					(thickness 0.2286)
				)
			)
		)
		(sheetname "MAC")
		(sheetfile "MAC.kicad_sch")
		(duplicate_pad_numbers_are_jumpers no)
		(pad "1" thru_hole circle
			(at 0 0 90)
			(size 2.54 2.54)
			(drill 2.0066)
			(layers "*.Cu" "*.Mask")
			(remove_unused_layers no)
			(net "MAC_TX")
			(thermal_bridge_angle 90)
		)
	)
	(footprint "Vault:RESC1005X40X25LL05T10"
		(layer "F.Cu")
		(at 127.6261 88.3162 180)
		(property "Reference" "R99"
			(at -0.6286 -0.826931 0)
			(unlocked yes)
			(layer "F.SilkS")
			(effects
				(font
					(size 0.762 0.762)
					(thickness 0.2286)
				)
			)
		)
		(property "Value" "49.9_1%_0402"
			(at -2.579871 8.823665 90)
			(unlocked yes)
			(layer "F.SilkS")
			(hide yes)
			(effects
				(font
					(size 0.762 0.762)
					(thickness 0.2286)
				)
			)
		)
		(sheetname "USBUart_DipSelects")
		(sheetfile "USBUart_DipSelects.kicad_sch")
		(duplicate_pad_numbers_are_jumpers no)
		(pad "1" smd rect
			(at -0.375 0 270)
			(size 0.45 0.5)
			(layers "F.Cu" "F.Mask" "F.Paste")
			(net "FPGA_MAC_PPS_DIFF_IN0")
		)
		(pad "2" smd rect
			(at 0.375 0 270)
			(size 0.45 0.5)
			(layers "F.Cu" "F.Mask" "F.Paste")
			(net "NetR99_2")
		)
	)
	(footprint "Vault:FP-SOD323-MFG"
		(layer "F.Cu")
		(at 220.5261 130.3162)
		(property "Reference" "D22"
			(at -0.2286 1.473069 180)
			(unlocked yes)
			(layer "F.SilkS")
			(effects
				(font
					(size 0.762 0.762)
					(thickness 0.2286)
				)
			)
		)
		(property "Value" "SD103AWS-7-F"
			(at -3.697481 8.341065 270)
			(unlocked yes)
			(layer "F.SilkS")
			(hide yes)
			(effects
				(font
					(size 0.762 0.762)
					(thickness 0.2286)
				)
			)
		)
		(sheetname "POWER")
		(sheetfile "POWER.kicad_sch")
		(duplicate_pad_numbers_are_jumpers no)
		(fp_line
			(start -0.9 -0.7)
			(end 0.9 -0.7)
			(stroke
				(width 0.2)
				(type solid)
			)
			(layer "F.SilkS")
		)
		(fp_line
			(start -0.9 -0.6)
			(end -0.9 -0.7)
			(stroke
				(width 0.2)
				(type solid)
			)
			(layer "F.SilkS")
		)
		(fp_line
			(start -0.9 0.7)
			(end -0.9 0.6)
			(stroke
				(width 0.2)
				(type solid)
			)
			(layer "F.SilkS")
		)
		(fp_line
			(start -0.9 0.7)
			(end 0.9 0.7)
			(stroke
				(width 0.2)
				(type solid)
			)
			(layer "F.SilkS")
		)
		(fp_line
			(start 0.9 -0.6)
			(end 0.9 -0.7)
			(stroke
				(width 0.2)
				(type solid)
			)
			(layer "F.SilkS")
		)
		(fp_line
			(start 0.9 0.7)
			(end 0.9 0.6)
			(stroke
				(width 0.2)
				(type solid)
			)
			(layer "F.SilkS")
		)
		(fp_circle
			(center -1.9 0)
			(end -1.9 -0.125)
			(stroke
				(width 0.25)
				(type solid)
			)
			(fill no)
			(layer "F.SilkS")
		)
		(fp_line
			(start -1.45 -0.8)
			(end 1.45 -0.8)
			(stroke
				(width 0.2)
				(type solid)
			)
			(layer "F.CrtYd")
		)
		(fp_line
			(start -1.45 0.8)
			(end -1.45 -0.8)
			(stroke
				(width 0.2)
				(type solid)
			)
			(layer "F.CrtYd")
		)
		(fp_line
			(start -1.45 0.8)
			(end 1.45 0.8)
			(stroke
				(width 0.2)
				(type solid)
			)
			(layer "F.CrtYd")
		)
		(fp_line
			(start 1.45 0.8)
			(end 1.45 -0.8)
			(stroke
				(width 0.2)
				(type solid)
			)
			(layer "F.CrtYd")
		)
		(fp_line
			(start -1.45 -0.8)
			(end 1.45 -0.8)
			(stroke
				(width 0.2)
				(type solid)
			)
			(layer "F.Fab")
		)
		(fp_line
			(start -1.45 0.8)
			(end -1.45 -0.8)
			(stroke
				(width 0.2)
				(type solid)
			)
			(layer "F.Fab")
		)
		(fp_line
			(start -1.45 0.8)
			(end 1.45 0.8)
			(stroke
				(width 0.2)
				(type solid)
			)
			(layer "F.Fab")
		)
		(fp_line
			(start -0.5 0)
			(end 0.5 0)
			(stroke
				(width 0.1)
				(type solid)
			)
			(layer "F.Fab")
		)
		(fp_line
			(start 0 0.5)
			(end 0 -0.5)
			(stroke
				(width 0.1)
				(type solid)
			)
			(layer "F.Fab")
		)
		(fp_line
			(start 1.45 0.8)
			(end 1.45 -0.8)
			(stroke
				(width 0.2)
				(type solid)
			)
			(layer "F.Fab")
		)
		(fp_text user "${REFERENCE}"
			(at -0.00001 0.10711 360)
			(unlocked yes)
			(layer "F.Fab")
			(effects
				(font
					(face "Arial")
					(size 0.63 0.63)
					(thickness 0.1)
				)
				(justify left bottom)
			)
		)
		(pad "1" smd rect
			(at -1.055 0)
			(size 0.59 0.45)
			(layers "F.Cu" "F.Mask" "F.Paste")
			(net "NetC68_1")
			(solder_mask_margin 0)
			(solder_paste_margin 0)
		)
		(pad "2" smd rect
			(at 1.055 0)
			(size 0.59 0.45)
			(layers "F.Cu" "F.Mask" "F.Paste")
			(net "P3V3_PVDD")
			(solder_mask_margin 0)
			(solder_paste_margin 0)
		)
	)
	(footprint "Vault:FP-CC0402-MFG"
		(layer "F.Cu")
		(at 233.2261 79.1162 180)
		(property "Reference" "C86"
			(at -0.2286 1.573069 0)
			(unlocked yes)
			(layer "F.SilkS")
			(effects
				(font
					(size 0.762 0.762)
					(thickness 0.2286)
				)
			)
		)
		(property "Value" "10nF_50V_0402"
			(at -2.592551 9.22982 90)
			(unlocked yes)
			(layer "F.SilkS")
			(hide yes)
			(effects
				(font
					(size 0.762 0.762)
					(thickness 0.2286)
				)
			)
		)
		(sheetname "USBUart_DipSelects")
		(sheetfile "USBUart_DipSelects.kicad_sch")
		(duplicate_pad_numbers_are_jumpers no)
		(fp_line
			(start 0.525 -0.675)
			(end -0.525 -0.675)
			(stroke
				(width 0.2)
				(type solid)
			)
			(layer "F.SilkS")
		)
		(fp_line
			(start 0.51967 0.68067)
			(end -0.53033 0.68067)
			(stroke
				(width 0.2)
				(type solid)
			)
			(layer "F.SilkS")
		)
		(fp_line
			(start 0.875 0.475)
			(end -0.875 0.475)
			(stroke
				(width 0.2)
				(type solid)
			)
			(layer "F.CrtYd")
		)
		(fp_line
			(start 0.875 -0.475)
			(end 0.875 0.475)
			(stroke
				(width 0.2)
				(type solid)
			)
			(layer "F.CrtYd")
		)
		(fp_line
			(start 0.875 -0.475)
			(end -0.875 -0.475)
			(stroke
				(width 0.2)
				(type solid)
			)
			(layer "F.CrtYd")
		)
		(fp_line
			(start -0.875 -0.475)
			(end -0.875 0.475)
			(stroke
				(width 0.2)
				(type solid)
			)
			(layer "F.CrtYd")
		)
		(fp_line
			(start 0.875 0.475)
			(end -0.875 0.475)
			(stroke
				(width 0.2)
				(type solid)
			)
			(layer "F.Fab")
		)
		(fp_line
			(start 0.875 -0.475)
			(end 0.875 0.475)
			(stroke
				(width 0.2)
				(type solid)
			)
			(layer "F.Fab")
		)
		(fp_line
			(start 0.875 -0.475)
			(end -0.875 -0.475)
			(stroke
				(width 0.2)
				(type solid)
			)
			(layer "F.Fab")
		)
		(fp_line
			(start 0.5 0)
			(end -0.5 0)
			(stroke
				(width 0.1)
				(type solid)
			)
			(layer "F.Fab")
		)
		(fp_line
			(start 0 -0.5)
			(end 0 0.5)
			(stroke
				(width 0.1)
				(type solid)
			)
			(layer "F.Fab")
		)
		(fp_line
			(start -0.875 -0.475)
			(end -0.875 0.475)
			(stroke
				(width 0.2)
				(type solid)
			)
			(layer "F.Fab")
		)
		(fp_text user "${REFERENCE}"
			(at -0.00001 0.09602 180)
			(unlocked yes)
			(layer "F.Fab")
			(effects
				(font
					(face "Arial")
					(size 0.63 0.63)
					(thickness 0.1)
				)
				(justify left bottom)
			)
		)
		(pad "1" smd rect
			(at -0.5 0 180)
			(size 0.5 0.5)
			(layers "F.Cu" "F.Mask" "F.Paste")
			(net "USB_VBUS")
			(solder_mask_margin 0)
			(solder_paste_margin 0)
		)
		(pad "2" smd rect
			(at 0.5 0 180)
			(size 0.5 0.5)
			(layers "F.Cu" "F.Mask" "F.Paste")
			(net "GND")
			(solder_mask_margin 0)
			(solder_paste_margin 0)
		)
	)
	(footprint "Vault:RESC1005X40X25LL05T10"
		(layer "F.Cu")
		(at 123.8261 86.2162 180)
		(property "Reference" "R105"
			(at 0.2714 7.273069 0)
			(unlocked yes)
			(layer "F.SilkS")
			(effects
				(font
					(size 0.762 0.762)
					(thickness 0.2286)
				)
			)
		)
		(property "Value" "DNI_49.9_1%_0402"
			(at -2.579871 11.74372 90)
			(unlocked yes)
			(layer "F.SilkS")
			(hide yes)
			(effects
				(font
					(size 0.762 0.762)
					(thickness 0.2286)
				)
			)
		)
		(sheetname "USBUart_DipSelects")
		(sheetfile "USBUart_DipSelects.kicad_sch")
		(duplicate_pad_numbers_are_jumpers no)
		(pad "1" smd rect
			(at -0.375 0 270)
			(size 0.45 0.5)
			(layers "F.Cu" "F.Mask" "F.Paste")
			(net "FPGA_MAC_PPS_OUT-")
		)
		(pad "2" smd rect
			(at 0.375 0 270)
			(size 0.45 0.5)
			(layers "F.Cu" "F.Mask" "F.Paste")
			(net "FPGA_MAC_PPSDIFF_OUT")
		)
	)
)
